(kicad_pcb
	(version 20260206)
	(generator "pcbnew")
	(generator_version "10.0")
	(general
		(thickness 1.6)
		(legacy_teardrops no)
	)
	(paper "A4")
	(title_block
		(title "pdpb — Lightning_PDPB_BRD.brd")
		(comment 1 "Lightning (Wiwynn / Facebook NVMe JBOF) / footprints 684-689 of 1140")
	)
	(layers
		(0 "F.Cu" signal "TOP")
		(4 "In1.Cu" signal "L2GND")
		(6 "In2.Cu" signal "L3")
		(8 "In3.Cu" signal "L4VCC")
		(10 "In4.Cu" signal "L5VCC")
		(12 "In5.Cu" signal "L6")
		(14 "In6.Cu" signal "L7GND")
		(2 "B.Cu" signal "BOTTOM")
		(9 "F.Adhes" user "F.Adhesive")
		(11 "B.Adhes" user "B.Adhesive")
		(13 "F.Paste" user "Package Geometry/Pastemask Top")
		(15 "B.Paste" user "Package Geometry/Pastemask Bottom")
		(5 "F.SilkS" user "Ref Des/Silkscreen Top")
		(7 "B.SilkS" user "Ref Des/Silkscreen Bottom")
		(1 "F.Mask" user "Board Geometry/Soldermask Top")
		(3 "B.Mask" user "Board Geometry/Soldermask Bottom")
		(17 "Dwgs.User" user "User.Drawings")
		(19 "Cmts.User" user "User.Comments")
		(21 "Eco1.User" user "User.Eco1")
		(23 "Eco2.User" user "User.Eco2")
		(25 "Edge.Cuts" user "Board Geometry/Outline")
		(27 "Margin" user)
		(31 "F.CrtYd" user "Package Geometry/Place Bound Top")
		(29 "B.CrtYd" user "Package Geometry/Place Bound Bottom")
		(35 "F.Fab" user "Ref Des/Assembly Top")
		(33 "B.Fab" user "Ref Des/Assembly Bottom")
	)
	(footprint ""
		(layer "F.Cu")
		(at 214.7824 -393.573)
		(property "Reference" "SR1093"
			(at 0 0 0)
			(layer "F.SilkS")
			(hide yes)
			(effects
				(font
					(size 1.27 1.27)
				)
			)
		)
		(property "Value" "4K7R2F-GP"
			(at 0.064008 -3.993896 0)
			(unlocked yes)
			(layer "F.Fab")
			(hide yes)
			(effects
				(font
					(size 1.016 1.016)
					(thickness 0.1524)
				)
			)
		)
		(property "Device Type" "R402H16"
			(at 0.064008 -5.517896 0)
			(unlocked yes)
			(layer "F.Fab")
			(hide yes)
			(effects
				(font
					(size 1.016 1.016)
					(thickness 0.1524)
				)
			)
		)
		(duplicate_pad_numbers_are_jumpers no)
		(fp_line
			(start -0.508 -0.9398)
			(end -0.508 0.9398)
			(stroke
				(width 0.1524)
				(type default)
			)
			(layer "F.SilkS")
		)
		(fp_line
			(start 0.508 -0.9398)
			(end -0.508 -0.9398)
			(stroke
				(width 0.1524)
				(type default)
			)
			(layer "F.SilkS")
		)
		(fp_rect
			(start -0.508 0.9398)
			(end 0.508 -0.9398)
			(stroke
				(width 0)
				(type default)
			)
			(fill no)
			(layer "F.CrtYd")
		)
		(fp_rect
			(start -0.508 0.9398)
			(end 0.508 -0.9398)
			(stroke
				(width 0)
				(type default)
			)
			(fill no)
			(layer "F.Fab")
		)
		(pad "1" smd custom
			(at 0 -0.4445)
			(size 0.1397 0.1397)
			(layers "F.Cu" "F.Mask" "F.Paste")
			(net "P3V3")
			(options
				(clearance outline)
				(anchor circle)
			)
			(primitives
				(gr_poly
					(pts
						(arc
							(start -0.1778 -0.2794)
							(mid -0.249642 -0.249642)
							(end -0.2794 -0.1778)
						)
						(arc
							(start -0.2794 0.1778)
							(mid -0.249642 0.249642)
							(end -0.1778 0.2794)
						)
						(arc
							(start 0.1778 0.2794)
							(mid 0.249642 0.249642)
							(end 0.2794 0.1778)
						)
						(arc
							(start 0.2794 -0.1778)
							(mid 0.249642 -0.249642)
							(end 0.1778 -0.2794)
						)
					)
					(width 0)
					(fill yes)
				)
			)
		)
		(pad "2" smd custom
			(at 0 0.4445)
			(size 0.1397 0.1397)
			(layers "F.Cu" "F.Mask" "F.Paste")
			(net "DUALPORTEN#1")
			(options
				(clearance outline)
				(anchor circle)
			)
			(primitives
				(gr_poly
					(pts
						(arc
							(start -0.1778 -0.2794)
							(mid -0.249642 -0.249642)
							(end -0.2794 -0.1778)
						)
						(arc
							(start -0.2794 0.1778)
							(mid -0.249642 0.249642)
							(end -0.1778 0.2794)
						)
						(arc
							(start 0.1778 0.2794)
							(mid 0.249642 0.249642)
							(end 0.2794 0.1778)
						)
						(arc
							(start 0.2794 -0.1778)
							(mid 0.249642 -0.249642)
							(end 0.1778 -0.2794)
						)
					)
					(width 0)
					(fill yes)
				)
			)
		)
	)
	(footprint ""
		(layer "F.Cu")
		(at 230.124 -429.133)
		(property "Reference" "PR9081"
			(at 0 0 0)
			(layer "F.SilkS")
			(hide yes)
			(effects
				(font
					(size 1.27 1.27)
				)
			)
		)
		(property "Value" "0R2J-2-GP"
			(at 0.064008 -3.993896 0)
			(unlocked yes)
			(layer "F.Fab")
			(hide yes)
			(effects
				(font
					(size 1.016 1.016)
					(thickness 0.1524)
				)
			)
		)
		(property "Device Type" "R402H16"
			(at 0.064008 -5.517896 0)
			(unlocked yes)
			(layer "F.Fab")
			(hide yes)
			(effects
				(font
					(size 1.016 1.016)
					(thickness 0.1524)
				)
			)
		)
		(duplicate_pad_numbers_are_jumpers no)
		(fp_line
			(start -0.508 -0.9398)
			(end -0.508 0.9398)
			(stroke
				(width 0.1524)
				(type default)
			)
			(layer "F.SilkS")
		)
		(fp_line
			(start 0.508 -0.9398)
			(end -0.508 -0.9398)
			(stroke
				(width 0.1524)
				(type default)
			)
			(layer "F.SilkS")
		)
		(fp_rect
			(start -0.508 0.9398)
			(end 0.508 -0.9398)
			(stroke
				(width 0)
				(type default)
			)
			(fill no)
			(layer "F.CrtYd")
		)
		(fp_rect
			(start -0.508 0.9398)
			(end 0.508 -0.9398)
			(stroke
				(width 0)
				(type default)
			)
			(fill no)
			(layer "F.Fab")
		)
		(pad "1" smd custom
			(at 0 -0.4445)
			(size 0.1397 0.1397)
			(layers "F.Cu" "F.Mask" "F.Paste")
			(net "P3V3_VO")
			(options
				(clearance outline)
				(anchor circle)
			)
			(primitives
				(gr_poly
					(pts
						(arc
							(start -0.1778 -0.2794)
							(mid -0.249642 -0.249642)
							(end -0.2794 -0.1778)
						)
						(arc
							(start -0.2794 0.1778)
							(mid -0.249642 0.249642)
							(end -0.1778 0.2794)
						)
						(arc
							(start 0.1778 0.2794)
							(mid 0.249642 0.249642)
							(end 0.2794 0.1778)
						)
						(arc
							(start 0.2794 -0.1778)
							(mid 0.249642 -0.249642)
							(end 0.1778 -0.2794)
						)
					)
					(width 0)
					(fill yes)
				)
			)
		)
		(pad "2" smd custom
			(at 0 0.4445)
			(size 0.1397 0.1397)
			(layers "F.Cu" "F.Mask" "F.Paste")
			(net "P3V3_CC_R")
			(options
				(clearance outline)
				(anchor circle)
			)
			(primitives
				(gr_poly
					(pts
						(arc
							(start -0.1778 -0.2794)
							(mid -0.249642 -0.249642)
							(end -0.2794 -0.1778)
						)
						(arc
							(start -0.2794 0.1778)
							(mid -0.249642 0.249642)
							(end -0.1778 0.2794)
						)
						(arc
							(start 0.1778 0.2794)
							(mid 0.249642 0.249642)
							(end 0.2794 0.1778)
						)
						(arc
							(start 0.2794 -0.1778)
							(mid 0.249642 -0.249642)
							(end 0.1778 -0.2794)
						)
					)
					(width 0)
					(fill yes)
				)
			)
		)
	)
	(footprint ""
		(layer "F.Cu")
		(at 70.000114 -483.497636)
		(property "Reference" "H2"
			(at 0 0 0)
			(layer "F.SilkS")
			(hide yes)
			(effects
				(font
					(size 1.27 1.27)
				)
			)
		)
		(property "Value" "GEN276X162R197X296-6-F-A-GP"
			(at -6.7183 4.1402 0)
			(unlocked yes)
			(layer "F.Fab")
			(hide yes)
			(effects
				(font
					(size 1.016 1.016)
					(thickness 0.1524)
				)
			)
		)
		(property "Device Type" "GEN276X162R197X296-6-F-A"
			(at -6.7183 2.6162 0)
			(unlocked yes)
			(layer "F.Fab")
			(hide yes)
			(effects
				(font
					(size 1.016 1.016)
					(thickness 0.1524)
				)
			)
		)
		(duplicate_pad_numbers_are_jumpers no)
		(fp_poly
			(pts
				(arc
					(start 2.723642 4.777232)
					(mid -0.000169 6.508462)
					(end -2.723896 4.776978)
				)
				(arc
					(start -2.723896 4.776978)
					(mid 0.000173 -5.499012)
					(end 2.723642 4.777232)
				)
			)
			(stroke
				(width 0)
				(type default)
			)
			(fill no)
			(layer "B.CrtYd")
		)
		(fp_poly
			(pts
				(arc
					(start 2.723642 4.777232)
					(mid -0.000169 6.508462)
					(end -2.723896 4.776978)
				)
				(arc
					(start -2.723896 4.776978)
					(mid 0.000173 -5.499012)
					(end 2.723642 4.777232)
				)
			)
			(stroke
				(width 0)
				(type default)
			)
			(fill no)
			(layer "F.CrtYd")
		)
		(fp_poly
			(pts
				(arc
					(start 2.723642 4.777232)
					(mid -0.000169 6.508462)
					(end -2.723896 4.776978)
				)
				(arc
					(start -2.723896 4.776978)
					(mid 0.000173 -5.499012)
					(end 2.723642 4.777232)
				)
			)
			(stroke
				(width 0)
				(type default)
			)
			(fill no)
			(layer "B.Fab")
		)
		(fp_poly
			(pts
				(arc
					(start 2.723642 4.777232)
					(mid -0.000169 6.508462)
					(end -2.723896 4.776978)
				)
				(arc
					(start -2.723896 4.776978)
					(mid 0.000173 -5.499012)
					(end 2.723642 4.777232)
				)
			)
			(stroke
				(width 0)
				(type default)
			)
			(fill no)
			(layer "F.Fab")
		)
		(pad "" np_thru_hole circle
			(at 0 0)
			(size 0.254 0.254)
			(drill 0.0254)
			(layers "*.Cu" "*.Mask")
			(clearance 3.135376)
			(thermal_gap 3.135376)
		)
		(pad "1" thru_hole circle
			(at 2.549906 0)
			(size 0.8636 0.8636)
			(drill 0.508)
			(layers "*.Cu" "*.Mask")
			(remove_unused_layers no)
			(net "GND")
			(clearance 0.8255)
			(thermal_gap 0.8255)
		)
		(pad "2" thru_hole circle
			(at 2.210054 -1.27)
			(size 0.8636 0.8636)
			(drill 0.508)
			(layers "*.Cu" "*.Mask")
			(remove_unused_layers no)
			(net "GND")
			(clearance 0.8255)
			(thermal_gap 0.8255)
		)
		(pad "3" thru_hole circle
			(at 1.27 -2.210054)
			(size 0.8636 0.8636)
			(drill 0.508)
			(layers "*.Cu" "*.Mask")
			(remove_unused_layers no)
			(net "GND")
			(clearance 0.8255)
			(thermal_gap 0.8255)
		)
		(pad "4" thru_hole circle
			(at -1.279906 -2.210054)
			(size 0.8636 0.8636)
			(drill 0.508)
			(layers "*.Cu" "*.Mask")
			(remove_unused_layers no)
			(net "GND")
			(clearance 0.8255)
			(thermal_gap 0.8255)
		)
		(pad "5" thru_hole circle
			(at -2.210054 -1.27)
			(size 0.8636 0.8636)
			(drill 0.508)
			(layers "*.Cu" "*.Mask")
			(remove_unused_layers no)
			(net "GND")
			(clearance 0.8255)
			(thermal_gap 0.8255)
		)
		(pad "6" thru_hole circle
			(at -2.549906 0)
			(size 0.8636 0.8636)
			(drill 0.508)
			(layers "*.Cu" "*.Mask")
			(remove_unused_layers no)
			(net "GND")
			(clearance 0.8255)
			(thermal_gap 0.8255)
		)
		(zone
			(layers "F.Cu" "B.Cu" "In1.Cu" "In2.Cu" "In3.Cu" "In4.Cu" "In5.Cu" "In6.Cu")
			(hatch none 0.5)
			(connect_pads
				(clearance 0)
			)
			(min_thickness 0.25)
			(keepout
				(tracks allowed)
				(vias not_allowed)
				(pads allowed)
				(copperpour not_allowed)
				(footprints allowed)
			)
			(placement
				(enabled no)
				(sheetname "")
			)
			(fill
				(thermal_gap 0.5)
				(thermal_bridge_width 0.5)
				(island_removal_mode 0)
			)
			(polygon
				(pts
					(arc
						(start 74.318114 -483.500684)
						(mid 65.682114 -483.500684)
						(end 74.318114 -483.500684)
					)
				)
			)
		)
		(zone
			(layers "F.Cu" "B.Cu" "In1.Cu" "In2.Cu" "In3.Cu" "In4.Cu" "In5.Cu" "In6.Cu")
			(hatch none 0.5)
			(connect_pads
				(clearance 0)
			)
			(min_thickness 0.25)
			(keepout
				(tracks not_allowed)
				(vias allowed)
				(pads allowed)
				(copperpour not_allowed)
				(footprints allowed)
			)
			(placement
				(enabled no)
				(sheetname "")
			)
			(fill
				(thermal_gap 0.5)
				(thermal_bridge_width 0.5)
				(island_removal_mode 0)
			)
			(polygon
				(pts
					(arc
						(start 72.339454 -481.888292)
						(mid 70.000194 -476.989189)
						(end 67.66052 -481.888292)
					)
					(arc
						(start 67.66052 -481.888292)
						(mid 67.906487 -482.328658)
						(end 67.991736 -482.825806)
					)
					(arc
						(start 67.991736 -483.497636)
						(mid 70.000114 -485.506014)
						(end 72.008238 -483.497636)
					)
					(arc
						(start 72.008238 -482.825806)
						(mid 72.093473 -482.328652)
						(end 72.339454 -481.888292)
					)
				)
			)
		)
	)
	(footprint ""
		(layer "F.Cu")
		(at 27.6098 -208.3562)
		(property "Reference" "PC1252"
			(at 0 0 0)
			(layer "F.SilkS")
			(hide yes)
			(effects
				(font
					(size 1.27 1.27)
				)
			)
		)
		(property "Value" "SCD1U50V3KX-GP"
			(at 0 -2.8194 0)
			(unlocked yes)
			(layer "F.Fab")
			(hide yes)
			(effects
				(font
					(size 1.016 1.016)
					(thickness 0.1524)
				)
			)
		)
		(property "Device Type" "C603H36"
			(at 0 -4.3434 0)
			(unlocked yes)
			(layer "F.Fab")
			(hide yes)
			(effects
				(font
					(size 1.016 1.016)
					(thickness 0.1524)
				)
			)
		)
		(duplicate_pad_numbers_are_jumpers no)
		(fp_line
			(start 0.508 0)
			(end -0.508 0)
			(stroke
				(width 0.2032)
				(type default)
			)
			(layer "F.SilkS")
		)
		(fp_rect
			(start -0.5842 1.3335)
			(end 0.5842 -1.3335)
			(stroke
				(width 0)
				(type default)
			)
			(fill no)
			(layer "F.CrtYd")
		)
		(fp_rect
			(start -0.5842 1.3335)
			(end 0.5842 -1.3335)
			(stroke
				(width 0)
				(type default)
			)
			(fill no)
			(layer "F.Fab")
		)
		(pad "1" smd custom
			(at 0 -0.762)
			(size 0.2159 0.2159)
			(layers "F.Cu" "F.Mask" "F.Paste")
			(net "P12V_SSD12")
			(options
				(clearance outline)
				(anchor circle)
			)
			(primitives
				(gr_poly
					(pts
						(arc
							(start -0.3302 -0.4318)
							(mid -0.402042 -0.402042)
							(end -0.4318 -0.3302)
						)
						(arc
							(start -0.4318 0.3302)
							(mid -0.402042 0.402042)
							(end -0.3302 0.4318)
						)
						(arc
							(start 0.3302 0.4318)
							(mid 0.402042 0.402042)
							(end 0.4318 0.3302)
						)
						(arc
							(start 0.4318 -0.3302)
							(mid 0.402042 -0.402042)
							(end 0.3302 -0.4318)
						)
					)
					(width 0)
					(fill yes)
				)
			)
		)
		(pad "2" smd custom
			(at 0 0.762)
			(size 0.2159 0.2159)
			(layers "F.Cu" "F.Mask" "F.Paste")
			(net "GND")
			(options
				(clearance outline)
				(anchor circle)
			)
			(primitives
				(gr_poly
					(pts
						(arc
							(start -0.3302 -0.4318)
							(mid -0.402042 -0.402042)
							(end -0.4318 -0.3302)
						)
						(arc
							(start -0.4318 0.3302)
							(mid -0.402042 0.402042)
							(end -0.3302 0.4318)
						)
						(arc
							(start 0.3302 0.4318)
							(mid 0.402042 0.402042)
							(end 0.4318 0.3302)
						)
						(arc
							(start 0.4318 -0.3302)
							(mid 0.402042 -0.402042)
							(end 0.3302 -0.4318)
						)
					)
					(width 0)
					(fill yes)
				)
			)
		)
	)
	(footprint ""
		(layer "F.Cu")
		(at 22.247606 -59.10961 180)
		(property "Reference" "R9874"
			(at 0 0 180)
			(layer "F.SilkS")
			(hide yes)
			(effects
				(font
					(size 1.27 1.27)
				)
			)
		)
		(property "Value" "0R2J-2-GP"
			(at 0.064008 -3.993896 180)
			(unlocked yes)
			(layer "F.Fab")
			(hide yes)
			(effects
				(font
					(size 1.016 1.016)
					(thickness 0.1524)
				)
			)
		)
		(property "Device Type" "R402H16"
			(at 0.064008 -5.517896 180)
			(unlocked yes)
			(layer "F.Fab")
			(hide yes)
			(effects
				(font
					(size 1.016 1.016)
					(thickness 0.1524)
				)
			)
		)
		(duplicate_pad_numbers_are_jumpers no)
		(fp_line
			(start 0.508 -0.9398)
			(end -0.508 -0.9398)
			(stroke
				(width 0.1524)
				(type default)
			)
			(layer "F.SilkS")
		)
		(fp_line
			(start -0.508 -0.9398)
			(end -0.508 0.9398)
			(stroke
				(width 0.1524)
				(type default)
			)
			(layer "F.SilkS")
		)
		(fp_rect
			(start -0.508 0.9398)
			(end 0.508 -0.9398)
			(stroke
				(width 0)
				(type default)
			)
			(fill no)
			(layer "F.CrtYd")
		)
		(fp_rect
			(start -0.508 0.9398)
			(end 0.508 -0.9398)
			(stroke
				(width 0)
				(type default)
			)
			(fill no)
			(layer "F.Fab")
		)
		(pad "1" smd custom
			(at 0 -0.4445 180)
			(size 0.1397 0.1397)
			(layers "F.Cu" "F.Mask" "F.Paste")
			(net "ATTN_LED_DR14_R")
			(options
				(clearance outline)
				(anchor circle)
			)
			(primitives
				(gr_poly
					(pts
						(arc
							(start -0.1778 -0.2794)
							(mid -0.249642 -0.249642)
							(end -0.2794 -0.1778)
						)
						(arc
							(start -0.2794 0.1778)
							(mid -0.249642 0.249642)
							(end -0.1778 0.2794)
						)
						(arc
							(start 0.1778 0.2794)
							(mid 0.249642 0.249642)
							(end 0.2794 0.1778)
						)
						(arc
							(start 0.2794 -0.1778)
							(mid 0.249642 -0.249642)
							(end 0.1778 -0.2794)
						)
					)
					(width 0)
					(fill yes)
				)
			)
		)
		(pad "2" smd custom
			(at 0 0.4445 180)
			(size 0.1397 0.1397)
			(layers "F.Cu" "F.Mask" "F.Paste")
			(net "ATTN_LED_DR14_N")
			(options
				(clearance outline)
				(anchor circle)
			)
			(primitives
				(gr_poly
					(pts
						(arc
							(start -0.1778 -0.2794)
							(mid -0.249642 -0.249642)
							(end -0.2794 -0.1778)
						)
						(arc
							(start -0.2794 0.1778)
							(mid -0.249642 0.249642)
							(end -0.1778 0.2794)
						)
						(arc
							(start 0.1778 0.2794)
							(mid 0.249642 0.249642)
							(end 0.2794 0.1778)
						)
						(arc
							(start 0.2794 -0.1778)
							(mid 0.249642 -0.249642)
							(end 0.1778 -0.2794)
						)
					)
					(width 0)
					(fill yes)
				)
			)
		)
	)
	(footprint ""
		(layer "F.Cu")
		(at 22.14245 -301.94885 90)
		(property "Reference" "R9827"
			(at 0 0 90)
			(layer "F.SilkS")
			(hide yes)
			(effects
				(font
					(size 1.27 1.27)
				)
			)
		)
		(property "Value" "1KR2J-1-GP"
			(at 0.064008 -3.993896 90)
			(unlocked yes)
			(layer "F.Fab")
			(hide yes)
			(effects
				(font
					(size 1.016 1.016)
					(thickness 0.1524)
				)
			)
		)
		(property "Device Type" "R402H16"
			(at 0.064008 -5.517896 90)
			(unlocked yes)
			(layer "F.Fab")
			(hide yes)
			(effects
				(font
					(size 1.016 1.016)
					(thickness 0.1524)
				)
			)
		)
		(duplicate_pad_numbers_are_jumpers no)
		(fp_line
			(start 0.508 -0.9398)
			(end -0.508 -0.9398)
			(stroke
				(width 0.1524)
				(type default)
			)
			(layer "F.SilkS")
		)
		(fp_line
			(start -0.508 -0.9398)
			(end -0.508 0.9398)
			(stroke
				(width 0.1524)
				(type default)
			)
			(layer "F.SilkS")
		)
		(fp_rect
			(start -0.508 0.9398)
			(end 0.508 -0.9398)
			(stroke
				(width 0)
				(type default)
			)
			(fill no)
			(layer "F.CrtYd")
		)
		(fp_rect
			(start -0.508 0.9398)
			(end 0.508 -0.9398)
			(stroke
				(width 0)
				(type default)
			)
			(fill no)
			(layer "F.Fab")
		)
		(pad "1" smd custom
			(at 0 -0.4445 90)
			(size 0.1397 0.1397)
			(layers "F.Cu" "F.Mask" "F.Paste")
			(net "SSD7_PWREN")
			(options
				(clearance outline)
				(anchor circle)
			)
			(primitives
				(gr_poly
					(pts
						(arc
							(start -0.1778 -0.2794)
							(mid -0.249642 -0.249642)
							(end -0.2794 -0.1778)
						)
						(arc
							(start -0.2794 0.1778)
							(mid -0.249642 0.249642)
							(end -0.1778 0.2794)
						)
						(arc
							(start 0.1778 0.2794)
							(mid 0.249642 0.249642)
							(end 0.2794 0.1778)
						)
						(arc
							(start 0.2794 -0.1778)
							(mid 0.249642 -0.249642)
							(end 0.1778 -0.2794)
						)
					)
					(width 0)
					(fill yes)
				)
			)
		)
		(pad "2" smd custom
			(at 0 0.4445 90)
			(size 0.1397 0.1397)
			(layers "F.Cu" "F.Mask" "F.Paste")
			(net "SSD7_PWREN_R")
			(options
				(clearance outline)
				(anchor circle)
			)
			(primitives
				(gr_poly
					(pts
						(arc
							(start -0.1778 -0.2794)
							(mid -0.249642 -0.249642)
							(end -0.2794 -0.1778)
						)
						(arc
							(start -0.2794 0.1778)
							(mid -0.249642 0.249642)
							(end -0.1778 0.2794)
						)
						(arc
							(start 0.1778 0.2794)
							(mid 0.249642 0.249642)
							(end 0.2794 0.1778)
						)
						(arc
							(start 0.2794 -0.1778)
							(mid 0.249642 -0.249642)
							(end 0.1778 -0.2794)
						)
					)
					(width 0)
					(fill yes)
				)
			)
		)
	)
)
